(kicad_pcb
	(version 20260206)
	(generator "pcbnew")
	(generator_version "10.0")
	(general
		(thickness 1.6)
		(legacy_teardrops no)
	)
	(paper "A4")
	(title_block
		(title "03242023_DA0F0TMBIJ0_F0T_Motherboard_J_brd_V01_OCP.brd")
		(comment 1 "Grand Teton / footprints 2466-2472 of 6105")
	)
	(layers
		(0 "F.Cu" signal "TOP")
		(4 "In1.Cu" signal "GND")
		(6 "In2.Cu" signal "IN1")
		(8 "In3.Cu" signal "GND1")
		(10 "In4.Cu" signal "IN2")
		(12 "In5.Cu" signal "GND2")
		(14 "In6.Cu" signal "IN3")
		(16 "In7.Cu" signal "GND3")
		(18 "In8.Cu" signal "VCC")
		(20 "In9.Cu" signal "VCC1")
		(22 "In10.Cu" signal "GND4")
		(24 "In11.Cu" signal "IN4")
		(26 "In12.Cu" signal "GND5")
		(28 "In13.Cu" signal "IN5")
		(30 "In14.Cu" signal "GND6")
		(32 "In15.Cu" signal "IN6")
		(34 "In16.Cu" signal "GND7")
		(2 "B.Cu" signal "BOTTOM")
		(9 "F.Adhes" user "F.Adhesive")
		(11 "B.Adhes" user "B.Adhesive")
		(13 "F.Paste" user "Package Geometry/Pastemask Top")
		(15 "B.Paste" user "Package Geometry/Pastemask Bottom")
		(5 "F.SilkS" user "Ref Des/Silkscreen Top")
		(7 "B.SilkS" user "Ref Des/Silkscreen Bottom")
		(1 "F.Mask" user "Board Geometry/Soldermask Top")
		(3 "B.Mask" user "Board Geometry/Soldermask Bottom")
		(17 "Dwgs.User" user "User.Drawings")
		(19 "Cmts.User" user "User.Comments")
		(21 "Eco1.User" user "User.Eco1")
		(23 "Eco2.User" user "User.Eco2")
		(25 "Edge.Cuts" user "Board Geometry/Outline")
		(27 "Margin" user)
		(31 "F.CrtYd" user "Package Geometry/Place Bound Top")
		(29 "B.CrtYd" user "Package Geometry/Place Bound Bottom")
		(35 "F.Fab" user "Ref Des/Assembly Top")
		(33 "B.Fab" user "Ref Des/Assembly Bottom")
	)
	(footprint ""
		(layer "F.Cu")
		(at 303.52873 -417.29914)
		(property "Reference" "R4575"
			(at 0 0 0)
			(layer "F.SilkS")
			(hide yes)
			(effects
				(font
					(size 1.27 1.27)
				)
			)
		)
		(property "Value" ""
			(at 0 0 0)
			(layer "F.Fab")
			(effects
				(font
					(size 1.27 1.27)
				)
			)
		)
		(duplicate_pad_numbers_are_jumpers no)
		(fp_line
			(start -0.7874 -0.4064)
			(end 0.7874 -0.4064)
			(stroke
				(width 0.1524)
				(type default)
			)
			(layer "F.SilkS")
		)
		(fp_line
			(start -0.7874 0.4064)
			(end -0.7874 -0.4064)
			(stroke
				(width 0.1524)
				(type default)
			)
			(layer "F.SilkS")
		)
		(fp_line
			(start 0.7874 -0.4064)
			(end 0.7874 0.4064)
			(stroke
				(width 0.1524)
				(type default)
			)
			(layer "F.SilkS")
		)
		(fp_line
			(start 0.7874 0.4064)
			(end -0.7874 0.4064)
			(stroke
				(width 0.1524)
				(type default)
			)
			(layer "F.SilkS")
		)
		(fp_line
			(start -0.67945 -0.305054)
			(end -0.12065 -0.305054)
			(stroke
				(width 0.1)
				(type default)
			)
			(layer "F.Fab")
		)
		(fp_line
			(start -0.67945 0.3048)
			(end -0.67945 -0.305054)
			(stroke
				(width 0.1)
				(type default)
			)
			(layer "F.Fab")
		)
		(fp_line
			(start -0.12065 -0.305054)
			(end -0.12065 -0.2794)
			(stroke
				(width 0.1)
				(type default)
			)
			(layer "F.Fab")
		)
		(fp_line
			(start -0.12065 -0.2794)
			(end 0.12065 -0.2794)
			(stroke
				(width 0.1)
				(type default)
			)
			(layer "F.Fab")
		)
		(fp_line
			(start -0.12065 0.2794)
			(end -0.12065 0.3048)
			(stroke
				(width 0.1)
				(type default)
			)
			(layer "F.Fab")
		)
		(fp_line
			(start -0.12065 0.3048)
			(end -0.67945 0.3048)
			(stroke
				(width 0.1)
				(type default)
			)
			(layer "F.Fab")
		)
		(fp_line
			(start 0.120396 0.2794)
			(end -0.12065 0.2794)
			(stroke
				(width 0.1)
				(type default)
			)
			(layer "F.Fab")
		)
		(fp_line
			(start 0.120396 0.3048)
			(end 0.120396 0.2794)
			(stroke
				(width 0.1)
				(type default)
			)
			(layer "F.Fab")
		)
		(fp_line
			(start 0.12065 -0.3048)
			(end 0.67945 -0.3048)
			(stroke
				(width 0.1)
				(type default)
			)
			(layer "F.Fab")
		)
		(fp_line
			(start 0.12065 -0.2794)
			(end 0.12065 -0.3048)
			(stroke
				(width 0.1)
				(type default)
			)
			(layer "F.Fab")
		)
		(fp_line
			(start 0.67945 -0.3048)
			(end 0.67945 0.3048)
			(stroke
				(width 0.1)
				(type default)
			)
			(layer "F.Fab")
		)
		(fp_line
			(start 0.67945 0.3048)
			(end 0.120396 0.3048)
			(stroke
				(width 0.1)
				(type default)
			)
			(layer "F.Fab")
		)
		(pad "1" smd circle
			(at -0.40005 0)
			(size 0 0)
			(layers "F.Cu" "F.Mask" "F.Paste")
			(net "GPU_3V3IO_RSVD0_FFU")
		)
		(pad "2" smd circle
			(at 0.40005 0)
			(size 0 0)
			(layers "F.Cu" "F.Mask" "F.Paste")
			(net "GPU_3V3IO_RSVD0_FFU_ISO")
		)
	)
	(footprint ""
		(layer "F.Cu")
		(at 350.691196 -61.506354)
		(property "Reference" "C1791"
			(at 0 0 0)
			(layer "F.SilkS")
			(hide yes)
			(effects
				(font
					(size 1.27 1.27)
				)
			)
		)
		(property "Value" ""
			(at 0 0 0)
			(layer "F.Fab")
			(effects
				(font
					(size 1.27 1.27)
				)
			)
		)
		(duplicate_pad_numbers_are_jumpers no)
		(fp_line
			(start -0.299974 -0.150114)
			(end 0.299974 -0.150114)
			(stroke
				(width 0.1)
				(type default)
			)
			(layer "F.Fab")
		)
		(fp_line
			(start -0.299974 0.150114)
			(end -0.299974 -0.150114)
			(stroke
				(width 0.1)
				(type default)
			)
			(layer "F.Fab")
		)
		(fp_line
			(start 0.299974 -0.150114)
			(end 0.299974 0.150114)
			(stroke
				(width 0.1)
				(type default)
			)
			(layer "F.Fab")
		)
		(fp_line
			(start 0.299974 0.150114)
			(end -0.299974 0.150114)
			(stroke
				(width 0.1)
				(type default)
			)
			(layer "F.Fab")
		)
		(pad "1" smd rect
			(at -0.2667 0)
			(size 0.3048 0.381)
			(layers "F.Cu" "F.Mask" "F.Paste")
			(net "DMI_CPU0_PCH_TX_C_DP<7>")
		)
		(pad "2" smd rect
			(at 0.2667 0)
			(size 0.3048 0.381)
			(layers "F.Cu" "F.Mask" "F.Paste")
			(net "DMI_CPU0_PCH_TX_DP<7>")
		)
		(zone
			(layer "In1.Cu")
			(hatch none 0.5)
			(connect_pads
				(clearance 0)
			)
			(min_thickness 0.25)
			(keepout
				(tracks not_allowed)
				(vias allowed)
				(pads allowed)
				(copperpour not_allowed)
				(footprints allowed)
			)
			(placement
				(enabled no)
				(sheetname "")
			)
			(fill
				(thermal_gap 0.5)
				(thermal_bridge_width 0.5)
				(island_removal_mode 0)
			)
			(polygon
				(pts
					(arc
						(start 350.297496 -61.265054)
						(mid 350.243614 -61.287372)
						(end 350.221296 -61.341254)
					)
					(arc
						(start 350.221296 -61.671454)
						(mid 350.243614 -61.725336)
						(end 350.297496 -61.747654)
					)
					(arc
						(start 350.551496 -61.747654)
						(mid 350.605378 -61.725336)
						(end 350.627696 -61.671454)
					)
					(arc
						(start 350.627696 -61.341254)
						(mid 350.605378 -61.287372)
						(end 350.551496 -61.265054)
					)
				)
			)
		)
		(zone
			(layer "In1.Cu")
			(hatch none 0.5)
			(connect_pads
				(clearance 0)
			)
			(min_thickness 0.25)
			(keepout
				(tracks not_allowed)
				(vias allowed)
				(pads allowed)
				(copperpour not_allowed)
				(footprints allowed)
			)
			(placement
				(enabled no)
				(sheetname "")
			)
			(fill
				(thermal_gap 0.5)
				(thermal_bridge_width 0.5)
				(island_removal_mode 0)
			)
			(polygon
				(pts
					(arc
						(start 350.830896 -61.265054)
						(mid 350.777014 -61.287372)
						(end 350.754696 -61.341254)
					)
					(arc
						(start 350.754696 -61.671454)
						(mid 350.777014 -61.725336)
						(end 350.830896 -61.747654)
					)
					(arc
						(start 351.084896 -61.747654)
						(mid 351.138778 -61.725336)
						(end 351.161096 -61.671454)
					)
					(arc
						(start 351.161096 -61.341254)
						(mid 351.138778 -61.287372)
						(end 351.084896 -61.265054)
					)
				)
			)
		)
	)
	(footprint ""
		(layer "F.Cu")
		(at 305.300888 -408.517344 -90)
		(property "Reference" "C902"
			(at 0 0 270)
			(layer "F.SilkS")
			(hide yes)
			(effects
				(font
					(size 1.27 1.27)
				)
			)
		)
		(property "Value" ""
			(at 0 0 270)
			(layer "F.Fab")
			(effects
				(font
					(size 1.27 1.27)
				)
			)
		)
		(duplicate_pad_numbers_are_jumpers no)
		(fp_line
			(start -0.299974 0.150114)
			(end -0.299974 -0.150114)
			(stroke
				(width 0.1)
				(type default)
			)
			(layer "F.Fab")
		)
		(fp_line
			(start 0.299974 0.150114)
			(end -0.299974 0.150114)
			(stroke
				(width 0.1)
				(type default)
			)
			(layer "F.Fab")
		)
		(fp_line
			(start -0.299974 -0.150114)
			(end 0.299974 -0.150114)
			(stroke
				(width 0.1)
				(type default)
			)
			(layer "F.Fab")
		)
		(fp_line
			(start 0.299974 -0.150114)
			(end 0.299974 0.150114)
			(stroke
				(width 0.1)
				(type default)
			)
			(layer "F.Fab")
		)
		(pad "1" smd rect
			(at -0.2667 0 270)
			(size 0.3048 0.381)
			(layers "F.Cu" "F.Mask" "F.Paste")
			(net "P5E_CPU0_PE0_TX_C_DN<15>")
		)
		(pad "2" smd rect
			(at 0.2667 0 270)
			(size 0.3048 0.381)
			(layers "F.Cu" "F.Mask" "F.Paste")
			(net "P5E_CPU0_PE0_TX_DN<15>")
		)
	)
	(footprint ""
		(layer "F.Cu")
		(at 424.204892 -387.314948 180)
		(property "Reference" "R2838"
			(at 0 0 180)
			(layer "F.SilkS")
			(hide yes)
			(effects
				(font
					(size 1.27 1.27)
				)
			)
		)
		(property "Value" ""
			(at 0 0 180)
			(layer "F.Fab")
			(effects
				(font
					(size 1.27 1.27)
				)
			)
		)
		(duplicate_pad_numbers_are_jumpers no)
		(fp_line
			(start 0.7874 0.4064)
			(end -0.7874 0.4064)
			(stroke
				(width 0.1524)
				(type default)
			)
			(layer "F.SilkS")
		)
		(fp_line
			(start 0.7874 -0.4064)
			(end 0.7874 0.4064)
			(stroke
				(width 0.1524)
				(type default)
			)
			(layer "F.SilkS")
		)
		(fp_line
			(start -0.7874 0.4064)
			(end -0.7874 -0.4064)
			(stroke
				(width 0.1524)
				(type default)
			)
			(layer "F.SilkS")
		)
		(fp_line
			(start -0.7874 -0.4064)
			(end 0.7874 -0.4064)
			(stroke
				(width 0.1524)
				(type default)
			)
			(layer "F.SilkS")
		)
		(fp_line
			(start 0.67945 0.3048)
			(end 0.120396 0.3048)
			(stroke
				(width 0.1)
				(type default)
			)
			(layer "F.Fab")
		)
		(fp_line
			(start 0.67945 -0.3048)
			(end 0.67945 0.3048)
			(stroke
				(width 0.1)
				(type default)
			)
			(layer "F.Fab")
		)
		(fp_line
			(start 0.12065 -0.2794)
			(end 0.12065 -0.3048)
			(stroke
				(width 0.1)
				(type default)
			)
			(layer "F.Fab")
		)
		(fp_line
			(start 0.12065 -0.3048)
			(end 0.67945 -0.3048)
			(stroke
				(width 0.1)
				(type default)
			)
			(layer "F.Fab")
		)
		(fp_line
			(start 0.120396 0.3048)
			(end 0.120396 0.2794)
			(stroke
				(width 0.1)
				(type default)
			)
			(layer "F.Fab")
		)
		(fp_line
			(start 0.120396 0.2794)
			(end -0.12065 0.2794)
			(stroke
				(width 0.1)
				(type default)
			)
			(layer "F.Fab")
		)
		(fp_line
			(start -0.12065 0.3048)
			(end -0.67945 0.3048)
			(stroke
				(width 0.1)
				(type default)
			)
			(layer "F.Fab")
		)
		(fp_line
			(start -0.12065 0.2794)
			(end -0.12065 0.3048)
			(stroke
				(width 0.1)
				(type default)
			)
			(layer "F.Fab")
		)
		(fp_line
			(start -0.12065 -0.2794)
			(end 0.12065 -0.2794)
			(stroke
				(width 0.1)
				(type default)
			)
			(layer "F.Fab")
		)
		(fp_line
			(start -0.12065 -0.305054)
			(end -0.12065 -0.2794)
			(stroke
				(width 0.1)
				(type default)
			)
			(layer "F.Fab")
		)
		(fp_line
			(start -0.67945 0.3048)
			(end -0.67945 -0.305054)
			(stroke
				(width 0.1)
				(type default)
			)
			(layer "F.Fab")
		)
		(fp_line
			(start -0.67945 -0.305054)
			(end -0.12065 -0.305054)
			(stroke
				(width 0.1)
				(type default)
			)
			(layer "F.Fab")
		)
		(pad "1" smd circle
			(at -0.40005 0 180)
			(size 0 0)
			(layers "F.Cu" "F.Mask" "F.Paste")
			(net "FM_SWB_PWRGD")
		)
		(pad "2" smd circle
			(at 0.40005 0 180)
			(size 0 0)
			(layers "F.Cu" "F.Mask" "F.Paste")
			(net "GND")
		)
	)
	(footprint ""
		(layer "F.Cu")
		(at 299.02023 -56.432196 180)
		(property "Reference" "R2980"
			(at 0 0 180)
			(layer "F.SilkS")
			(hide yes)
			(effects
				(font
					(size 1.27 1.27)
				)
			)
		)
		(property "Value" ""
			(at 0 0 180)
			(layer "F.Fab")
			(effects
				(font
					(size 1.27 1.27)
				)
			)
		)
		(duplicate_pad_numbers_are_jumpers no)
		(fp_line
			(start 0.7874 0.4064)
			(end -0.7874 0.4064)
			(stroke
				(width 0.1524)
				(type default)
			)
			(layer "F.SilkS")
		)
		(fp_line
			(start 0.7874 -0.4064)
			(end 0.7874 0.4064)
			(stroke
				(width 0.1524)
				(type default)
			)
			(layer "F.SilkS")
		)
		(fp_line
			(start -0.7874 0.4064)
			(end -0.7874 -0.4064)
			(stroke
				(width 0.1524)
				(type default)
			)
			(layer "F.SilkS")
		)
		(fp_line
			(start -0.7874 -0.4064)
			(end 0.7874 -0.4064)
			(stroke
				(width 0.1524)
				(type default)
			)
			(layer "F.SilkS")
		)
		(fp_line
			(start 0.67945 0.3048)
			(end 0.120396 0.3048)
			(stroke
				(width 0.1)
				(type default)
			)
			(layer "F.Fab")
		)
		(fp_line
			(start 0.67945 -0.3048)
			(end 0.67945 0.3048)
			(stroke
				(width 0.1)
				(type default)
			)
			(layer "F.Fab")
		)
		(fp_line
			(start 0.12065 -0.2794)
			(end 0.12065 -0.3048)
			(stroke
				(width 0.1)
				(type default)
			)
			(layer "F.Fab")
		)
		(fp_line
			(start 0.12065 -0.3048)
			(end 0.67945 -0.3048)
			(stroke
				(width 0.1)
				(type default)
			)
			(layer "F.Fab")
		)
		(fp_line
			(start 0.120396 0.3048)
			(end 0.120396 0.2794)
			(stroke
				(width 0.1)
				(type default)
			)
			(layer "F.Fab")
		)
		(fp_line
			(start 0.120396 0.2794)
			(end -0.12065 0.2794)
			(stroke
				(width 0.1)
				(type default)
			)
			(layer "F.Fab")
		)
		(fp_line
			(start -0.12065 0.3048)
			(end -0.67945 0.3048)
			(stroke
				(width 0.1)
				(type default)
			)
			(layer "F.Fab")
		)
		(fp_line
			(start -0.12065 0.2794)
			(end -0.12065 0.3048)
			(stroke
				(width 0.1)
				(type default)
			)
			(layer "F.Fab")
		)
		(fp_line
			(start -0.12065 -0.2794)
			(end 0.12065 -0.2794)
			(stroke
				(width 0.1)
				(type default)
			)
			(layer "F.Fab")
		)
		(fp_line
			(start -0.12065 -0.305054)
			(end -0.12065 -0.2794)
			(stroke
				(width 0.1)
				(type default)
			)
			(layer "F.Fab")
		)
		(fp_line
			(start -0.67945 0.3048)
			(end -0.67945 -0.305054)
			(stroke
				(width 0.1)
				(type default)
			)
			(layer "F.Fab")
		)
		(fp_line
			(start -0.67945 -0.305054)
			(end -0.12065 -0.305054)
			(stroke
				(width 0.1)
				(type default)
			)
			(layer "F.Fab")
		)
		(pad "1" smd circle
			(at -0.40005 0 180)
			(size 0 0)
			(layers "F.Cu" "F.Mask" "F.Paste")
			(net "FM_BOARD_SKU_ID2")
		)
		(pad "2" smd circle
			(at 0.40005 0 180)
			(size 0 0)
			(layers "F.Cu" "F.Mask" "F.Paste")
			(net "GND")
		)
	)
	(footprint ""
		(layer "F.Cu")
		(at 295.25595 -417.2204)
		(property "Reference" "R4574"
			(at 0 0 0)
			(layer "F.SilkS")
			(hide yes)
			(effects
				(font
					(size 1.27 1.27)
				)
			)
		)
		(property "Value" ""
			(at 0 0 0)
			(layer "F.Fab")
			(effects
				(font
					(size 1.27 1.27)
				)
			)
		)
		(duplicate_pad_numbers_are_jumpers no)
		(fp_line
			(start -0.7874 -0.4064)
			(end 0.7874 -0.4064)
			(stroke
				(width 0.1524)
				(type default)
			)
			(layer "F.SilkS")
		)
		(fp_line
			(start -0.7874 0.4064)
			(end -0.7874 -0.4064)
			(stroke
				(width 0.1524)
				(type default)
			)
			(layer "F.SilkS")
		)
		(fp_line
			(start 0.7874 -0.4064)
			(end 0.7874 0.4064)
			(stroke
				(width 0.1524)
				(type default)
			)
			(layer "F.SilkS")
		)
		(fp_line
			(start 0.7874 0.4064)
			(end -0.7874 0.4064)
			(stroke
				(width 0.1524)
				(type default)
			)
			(layer "F.SilkS")
		)
		(fp_line
			(start -0.67945 -0.305054)
			(end -0.12065 -0.305054)
			(stroke
				(width 0.1)
				(type default)
			)
			(layer "F.Fab")
		)
		(fp_line
			(start -0.67945 0.3048)
			(end -0.67945 -0.305054)
			(stroke
				(width 0.1)
				(type default)
			)
			(layer "F.Fab")
		)
		(fp_line
			(start -0.12065 -0.305054)
			(end -0.12065 -0.2794)
			(stroke
				(width 0.1)
				(type default)
			)
			(layer "F.Fab")
		)
		(fp_line
			(start -0.12065 -0.2794)
			(end 0.12065 -0.2794)
			(stroke
				(width 0.1)
				(type default)
			)
			(layer "F.Fab")
		)
		(fp_line
			(start -0.12065 0.2794)
			(end -0.12065 0.3048)
			(stroke
				(width 0.1)
				(type default)
			)
			(layer "F.Fab")
		)
		(fp_line
			(start -0.12065 0.3048)
			(end -0.67945 0.3048)
			(stroke
				(width 0.1)
				(type default)
			)
			(layer "F.Fab")
		)
		(fp_line
			(start 0.120396 0.2794)
			(end -0.12065 0.2794)
			(stroke
				(width 0.1)
				(type default)
			)
			(layer "F.Fab")
		)
		(fp_line
			(start 0.120396 0.3048)
			(end 0.120396 0.2794)
			(stroke
				(width 0.1)
				(type default)
			)
			(layer "F.Fab")
		)
		(fp_line
			(start 0.12065 -0.3048)
			(end 0.67945 -0.3048)
			(stroke
				(width 0.1)
				(type default)
			)
			(layer "F.Fab")
		)
		(fp_line
			(start 0.12065 -0.2794)
			(end 0.12065 -0.3048)
			(stroke
				(width 0.1)
				(type default)
			)
			(layer "F.Fab")
		)
		(fp_line
			(start 0.67945 -0.3048)
			(end 0.67945 0.3048)
			(stroke
				(width 0.1)
				(type default)
			)
			(layer "F.Fab")
		)
		(fp_line
			(start 0.67945 0.3048)
			(end 0.120396 0.3048)
			(stroke
				(width 0.1)
				(type default)
			)
			(layer "F.Fab")
		)
		(pad "1" smd circle
			(at -0.40005 0)
			(size 0 0)
			(layers "F.Cu" "F.Mask" "F.Paste")
			(net "PRSNT_CABLE_GPU_A1_N")
		)
		(pad "2" smd circle
			(at 0.40005 0)
			(size 0 0)
			(layers "F.Cu" "F.Mask" "F.Paste")
			(net "PRSNT_CABLE_GPU_A1_ISO_N")
		)
	)
	(footprint ""
		(layer "F.Cu")
		(at 127.804926 -119.810784 90)
		(property "Reference" "R4054"
			(at 0 0 90)
			(layer "F.SilkS")
			(hide yes)
			(effects
				(font
					(size 1.27 1.27)
				)
			)
		)
		(property "Value" ""
			(at 0 0 90)
			(layer "F.Fab")
			(effects
				(font
					(size 1.27 1.27)
				)
			)
		)
		(duplicate_pad_numbers_are_jumpers no)
		(fp_line
			(start 0.7874 -0.4064)
			(end 0.7874 0.4064)
			(stroke
				(width 0.1524)
				(type default)
			)
			(layer "F.SilkS")
		)
		(fp_line
			(start -0.7874 -0.4064)
			(end 0.7874 -0.4064)
			(stroke
				(width 0.1524)
				(type default)
			)
			(layer "F.SilkS")
		)
		(fp_line
			(start 0.7874 0.4064)
			(end -0.7874 0.4064)
			(stroke
				(width 0.1524)
				(type default)
			)
			(layer "F.SilkS")
		)
		(fp_line
			(start -0.7874 0.4064)
			(end -0.7874 -0.4064)
			(stroke
				(width 0.1524)
				(type default)
			)
			(layer "F.SilkS")
		)
		(fp_line
			(start -0.12065 -0.305054)
			(end -0.12065 -0.2794)
			(stroke
				(width 0.1)
				(type default)
			)
			(layer "F.Fab")
		)
		(fp_line
			(start -0.67945 -0.305054)
			(end -0.12065 -0.305054)
			(stroke
				(width 0.1)
				(type default)
			)
			(layer "F.Fab")
		)
		(fp_line
			(start 0.67945 -0.3048)
			(end 0.67945 0.3048)
			(stroke
				(width 0.1)
				(type default)
			)
			(layer "F.Fab")
		)
		(fp_line
			(start 0.12065 -0.3048)
			(end 0.67945 -0.3048)
			(stroke
				(width 0.1)
				(type default)
			)
			(layer "F.Fab")
		)
		(fp_line
			(start 0.12065 -0.2794)
			(end 0.12065 -0.3048)
			(stroke
				(width 0.1)
				(type default)
			)
			(layer "F.Fab")
		)
		(fp_line
			(start -0.12065 -0.2794)
			(end 0.12065 -0.2794)
			(stroke
				(width 0.1)
				(type default)
			)
			(layer "F.Fab")
		)
		(fp_line
			(start 0.120396 0.2794)
			(end -0.12065 0.2794)
			(stroke
				(width 0.1)
				(type default)
			)
			(layer "F.Fab")
		)
		(fp_line
			(start -0.12065 0.2794)
			(end -0.12065 0.3048)
			(stroke
				(width 0.1)
				(type default)
			)
			(layer "F.Fab")
		)
		(fp_line
			(start 0.67945 0.3048)
			(end 0.120396 0.3048)
			(stroke
				(width 0.1)
				(type default)
			)
			(layer "F.Fab")
		)
		(fp_line
			(start 0.120396 0.3048)
			(end 0.120396 0.2794)
			(stroke
				(width 0.1)
				(type default)
			)
			(layer "F.Fab")
		)
		(fp_line
			(start -0.12065 0.3048)
			(end -0.67945 0.3048)
			(stroke
				(width 0.1)
				(type default)
			)
			(layer "F.Fab")
		)
		(fp_line
			(start -0.67945 0.3048)
			(end -0.67945 -0.305054)
			(stroke
				(width 0.1)
				(type default)
			)
			(layer "F.Fab")
		)
		(pad "1" smd circle
			(at -0.40005 0 90)
			(size 0 0)
			(layers "F.Cu" "F.Mask" "F.Paste")
			(net "PD_GTL2014_BMC_JTAG_DIR_1")
		)
		(pad "2" smd circle
			(at 0.40005 0 90)
			(size 0 0)
			(layers "F.Cu" "F.Mask" "F.Paste")
			(net "GND")
		)
	)
)
